(kicad_pcb
	(version 20241229)
	(generator "pcbnew")
	(generator_version "9.0")
	(general
		(thickness 1.6)
		(legacy_teardrops no)
	)
	(paper "A4")
	(title_block
		(title "OCuLink to PCIe adapter")
		(date "2025-06-18")
		(rev "1.0.0")
		(company "Antmicro Ltd")
		(comment 1 "www.antmicro.com")
		(comment 9 "footprints 26-28 of 159")
	)
	(layers
		(0 "F.Cu" signal)
		(4 "In1.Cu" signal)
		(6 "In2.Cu" signal)
		(2 "B.Cu" signal)
		(9 "F.Adhes" user "F.Adhesive")
		(11 "B.Adhes" user "B.Adhesive")
		(13 "F.Paste" user)
		(15 "B.Paste" user)
		(5 "F.SilkS" user "F.Silkscreen")
		(7 "B.SilkS" user "B.Silkscreen")
		(1 "F.Mask" user)
		(3 "B.Mask" user)
		(17 "Dwgs.User" user "User.Drawings")
		(19 "Cmts.User" user "User.Comments")
		(21 "Eco1.User" user "User.Eco1")
		(23 "Eco2.User" user "User.Eco2")
		(25 "Edge.Cuts" user)
		(27 "Margin" user)
		(31 "F.CrtYd" user "F.Courtyard")
		(29 "B.CrtYd" user "B.Courtyard")
		(35 "F.Fab" user)
		(33 "B.Fab" user)
	)
	(footprint "antmicro-footprints:QFN-20-1EP_3x3mm_P0.45mm"
		(layer "F.Cu")
		(at 123.75 133.025001 180)
		(property "Reference" "U1"
			(at -0.65 2.825001 180)
			(layer "F.SilkS")
			(effects
				(font
					(size 0.7 0.7)
					(thickness 0.15)
				)
				(justify right top)
			)
		)
		(property "Value" "TPS56C230"
			(at 0 2.897999 0)
			(layer "F.Fab")
			(effects
				(font
					(size 0.7 0.7)
					(thickness 0.15)
				)
				(justify right top)
			)
		)
		(property "Datasheet" "https://www.ti.com/lit/ds/symlink/tps56c230.pdf"
			(at 0 0 0)
			(layer "F.Fab")
			(hide yes)
			(effects
				(font
					(size 1.27 1.27)
					(thickness 0.15)
				)
			)
		)
		(property "Description" "DC/DC converter"
			(at 0 0 0)
			(layer "F.Fab")
			(hide yes)
			(effects
				(font
					(size 1.27 1.27)
					(thickness 0.15)
				)
			)
		)
		(property "Manufacturer" "Texas Instruments"
			(at 0 0 180)
			(unlocked yes)
			(layer "F.Fab")
			(hide yes)
			(effects
				(font
					(size 1 1)
					(thickness 0.15)
				)
			)
		)
		(property "MPN" "TPS56C230RJER"
			(at 0 0 180)
			(unlocked yes)
			(layer "F.Fab")
			(hide yes)
			(effects
				(font
					(size 1 1)
					(thickness 0.15)
				)
			)
		)
		(property "Author" "Antmicro"
			(at 0 0 180)
			(unlocked yes)
			(layer "F.Fab")
			(hide yes)
			(effects
				(font
					(size 1 1)
					(thickness 0.15)
				)
			)
		)
		(property "License" "Apache-2.0"
			(at 0 0 180)
			(unlocked yes)
			(layer "F.Fab")
			(hide yes)
			(effects
				(font
					(size 1 1)
					(thickness 0.15)
				)
			)
		)
		(sheetname "/Power/")
		(sheetfile "power.kicad_sch")
		(attr smd)
		(fp_line
			(start 1.5 -1.5)
			(end 1.5 -1.2)
			(stroke
				(width 0.15)
				(type solid)
			)
			(layer "F.SilkS")
		)
		(fp_line
			(start 1.499 1.5)
			(end 1.499 1.202)
			(stroke
				(width 0.15)
				(type solid)
			)
			(layer "F.SilkS")
		)
		(fp_line
			(start 1.202 -1.5)
			(end 1.5 -1.5)
			(stroke
				(width 0.15)
				(type solid)
			)
			(layer "F.SilkS")
		)
		(fp_line
			(start 1.201 1.5)
			(end 1.499 1.5)
			(stroke
				(width 0.15)
				(type solid)
			)
			(layer "F.SilkS")
		)
		(fp_line
			(start -1.2 1.498)
			(end -1.5 1.498)
			(stroke
				(width 0.15)
				(type solid)
			)
			(layer "F.SilkS")
		)
		(fp_line
			(start -1.5 1.498)
			(end -1.5 1.2)
			(stroke
				(width 0.15)
				(type solid)
			)
			(layer "F.SilkS")
		)
		(fp_line
			(start -1.5 -1.201)
			(end -1.5 -1.499)
			(stroke
				(width 0.15)
				(type solid)
			)
			(layer "F.SilkS")
		)
		(fp_line
			(start -1.5 -1.499)
			(end -1.2 -1.499)
			(stroke
				(width 0.15)
				(type solid)
			)
			(layer "F.SilkS")
		)
		(fp_circle
			(center -1.75 -1.15)
			(end -1.7 -1.15)
			(stroke
				(width 0.15)
				(type solid)
			)
			(fill yes)
			(layer "F.SilkS")
		)
		(fp_rect
			(start -1.8 -1.8)
			(end 1.8 1.8)
			(stroke
				(width 0.05)
				(type solid)
			)
			(fill no)
			(layer "F.CrtYd")
		)
		(fp_line
			(start 1.499 1.499)
			(end 1.499 -1.5)
			(stroke
				(width 0.15)
				(type solid)
			)
			(layer "F.Fab")
		)
		(fp_line
			(start 1.499 -1.5)
			(end -0.5 -1.5)
			(stroke
				(width 0.15)
				(type solid)
			)
			(layer "F.Fab")
		)
		(fp_line
			(start -0.5 -1.5)
			(end -1.5 -0.5)
			(stroke
				(width 0.15)
				(type solid)
			)
			(layer "F.Fab")
		)
		(fp_line
			(start -1.5 1.499)
			(end 1.499 1.499)
			(stroke
				(width 0.15)
				(type solid)
			)
			(layer "F.Fab")
		)
		(fp_line
			(start -1.5 -0.5)
			(end -1.5 1.499)
			(stroke
				(width 0.15)
				(type solid)
			)
			(layer "F.Fab")
		)
		(fp_text user "License: Apache-2.0"
			(at -2.1844 2.844799 0)
			(layer "F.Fab")
			(effects
				(font
					(size 0.7 0.7)
					(thickness 0.15)
				)
				(justify right top)
			)
		)
		(fp_text user "Author: Antmicro"
			(at -2.184401 4.0448 0)
			(layer "F.Fab")
			(effects
				(font
					(size 0.7 0.7)
					(thickness 0.15)
				)
				(justify right top)
			)
		)
		(fp_text user "${REFERENCE}"
			(at -0.025 0 0)
			(layer "F.Fab")
			(effects
				(font
					(size 0.7 0.7)
					(thickness 0.15)
				)
				(justify right top)
			)
		)
		(pad "1" smd oval
			(at -1.401 -0.903 270)
			(size 0.2 0.6)
			(layers "F.Cu" "F.Mask" "F.Paste")
			(net 85 "/Power/3V3_BST")
			(pinfunction "BST")
			(pintype "passive")
		)
		(pad "2" smd oval
			(at -1.401 -0.453 270)
			(size 0.2 0.6)
			(layers "F.Cu" "F.Mask" "F.Paste")
			(net 87 "+12V")
			(pinfunction "V_{IN}")
			(pintype "power_in")
		)
		(pad "3" smd oval
			(at -1.401 0 270)
			(size 0.2 0.6)
			(layers "F.Cu" "F.Mask" "F.Paste")
			(net 87 "+12V")
			(pinfunction "V_{IN}")
			(pintype "passive")
		)
		(pad "4" smd oval
			(at -1.401 0.45 270)
			(size 0.2 0.6)
			(layers "F.Cu" "F.Mask" "F.Paste")
			(net 87 "+12V")
			(pinfunction "V_{IN}")
			(pintype "passive")
		)
		(pad "5" smd oval
			(at -1.401 0.9 270)
			(size 0.2 0.6)
			(layers "F.Cu" "F.Mask" "F.Paste")
			(net 87 "+12V")
			(pinfunction "V_{IN}")
			(pintype "passive")
		)
		(pad "6" smd oval
			(at -0.903 1.398 180)
			(size 0.2 0.6)
			(layers "F.Cu" "F.Mask" "F.Paste")
			(net 86 "/Power/3V3_SW")
			(pinfunction "SW")
			(pintype "passive")
		)
		(pad "7" smd oval
			(at -0.453 1.398 180)
			(size 0.2 0.6)
			(layers "F.Cu" "F.Mask" "F.Paste")
			(net 66 "GND")
			(pinfunction "PGND")
			(pintype "passive")
		)
		(pad "8" smd oval
			(at 0 1.398 180)
			(size 0.2 0.6)
			(layers "F.Cu" "F.Mask" "F.Paste")
			(net 66 "GND")
			(pinfunction "PGND")
			(pintype "passive")
		)
		(pad "9" smd oval
			(at 0.45 1.398 180)
			(size 0.2 0.6)
			(layers "F.Cu" "F.Mask" "F.Paste")
			(net 105 "/Power/3V3_PG")
			(pinfunction "PG")
			(pintype "passive")
		)
		(pad "10" smd oval
			(at 0.9 1.398 180)
			(size 0.2 0.6)
			(layers "F.Cu" "F.Mask" "F.Paste")
			(net 110 "unconnected-(U1-NC-Pad10)")
			(pinfunction "NC")
			(pintype "no_connect")
		)
		(pad "11" smd oval
			(at 1.398 0.9 270)
			(size 0.2 0.6)
			(layers "F.Cu" "F.Mask" "F.Paste")
			(net 111 "unconnected-(U1-SS-Pad11)")
			(pinfunction "SS")
			(pintype "passive+no_connect")
		)
		(pad "12" smd oval
			(at 1.398 0.45 270)
			(size 0.2 0.6)
			(layers "F.Cu" "F.Mask" "F.Paste")
			(net 106 "/Power/3V3_EN")
			(pinfunction "EN")
			(pintype "passive")
		)
		(pad "13" smd oval
			(at 1.398 0 270)
			(size 0.2 0.6)
			(layers "F.Cu" "F.Mask" "F.Paste")
			(net 66 "GND")
			(pinfunction "AGND")
			(pintype "passive")
		)
		(pad "14" smd oval
			(at 1.398 -0.453 270)
			(size 0.2 0.6)
			(layers "F.Cu" "F.Mask" "F.Paste")
			(net 108 "/Power/3V3_FB")
			(pinfunction "FB")
			(pintype "passive")
		)
		(pad "15" smd oval
			(at 1.398 -0.903 270)
			(size 0.2 0.6)
			(layers "F.Cu" "F.Mask" "F.Paste")
			(net 107 "/Power/3V3_MODE")
			(pinfunction "MODE")
			(pintype "passive")
		)
		(pad "16" smd oval
			(at 0.9 -1.401 180)
			(size 0.2 0.6)
			(layers "F.Cu" "F.Mask" "F.Paste")
			(net 109 "unconnected-(U1-NC-Pad16)")
			(pinfunction "NC")
			(pintype "no_connect")
		)
		(pad "17" smd oval
			(at 0.45 -1.401 180)
			(size 0.2 0.6)
			(layers "F.Cu" "F.Mask" "F.Paste")
			(net 88 "/Power/3V3_VCC")
			(pinfunction "V_{CC}")
			(pintype "passive")
		)
		(pad "18" smd oval
			(at 0 -1.401 180)
			(size 0.2 0.6)
			(layers "F.Cu" "F.Mask" "F.Paste")
			(net 66 "GND")
			(pinfunction "PGND")
			(pintype "passive")
		)
		(pad "19" smd oval
			(at -0.453 -1.401 180)
			(size 0.2 0.6)
			(layers "F.Cu" "F.Mask" "F.Paste")
			(net 86 "/Power/3V3_SW")
			(pinfunction "SW")
			(pintype "passive")
		)
		(pad "20" smd oval
			(at -0.903 -1.401 180)
			(size 0.2 0.6)
			(layers "F.Cu" "F.Mask" "F.Paste")
			(net 86 "/Power/3V3_SW")
			(pinfunction "SW")
			(pintype "passive")
		)
		(pad "21" smd roundrect
			(at 0 0 180)
			(size 1 1)
			(layers "F.Cu" "F.Mask" "F.Paste")
			(roundrect_rratio 0.1)
			(net 66 "GND")
			(pinfunction "PGND")
			(pintype "passive")
		)
	)
	(footprint "antmicro-footprints:L_WE-MAPI-4020"
		(layer "F.Cu")
		(at 125.9 137.55 -90)
		(property "Reference" "L1"
			(at 3.65 0.7 180)
			(layer "F.SilkS")
			(effects
				(font
					(size 0.7 0.7)
					(thickness 0.15)
				)
				(justify left bottom)
			)
		)
		(property "Value" "L_1u8_6.8A_WE-MAPI-4020"
			(at -2.4 3.4 90)
			(layer "F.Fab")
			(effects
				(font
					(size 0.7 0.7)
					(thickness 0.15)
				)
				(justify left bottom)
			)
		)
		(property "Datasheet" "https://www.we-online.com/components/products/datasheet/74438356018.pdf"
			(at 0 0 90)
			(layer "F.Fab")
			(hide yes)
			(effects
				(font
					(size 1.27 1.27)
					(thickness 0.15)
				)
			)
		)
		(property "Description" "Power Inductors - SMD WE-MAPI 1.8uH 4.6A DCR=30mOhms AEC-Q200"
			(at 0 0 90)
			(layer "F.Fab")
			(hide yes)
			(effects
				(font
					(size 1.27 1.27)
					(thickness 0.15)
				)
			)
		)
		(property "Val" "1u8/6.8A"
			(at 0 0 270)
			(unlocked yes)
			(layer "F.Fab")
			(hide yes)
			(effects
				(font
					(size 1 1)
					(thickness 0.15)
				)
			)
		)
		(property "Manufacturer" "Würth Elektronik"
			(at 0 0 270)
			(unlocked yes)
			(layer "F.Fab")
			(hide yes)
			(effects
				(font
					(size 1 1)
					(thickness 0.15)
				)
			)
		)
		(property "MPN" "74438356018"
			(at 0 0 270)
			(unlocked yes)
			(layer "F.Fab")
			(hide yes)
			(effects
				(font
					(size 1 1)
					(thickness 0.15)
				)
			)
		)
		(property "ISat" "6.5 A"
			(at 0 0 270)
			(unlocked yes)
			(layer "F.Fab")
			(hide yes)
			(effects
				(font
					(size 1 1)
					(thickness 0.15)
				)
			)
		)
		(property "IMax" "6.8 A"
			(at 0 0 270)
			(unlocked yes)
			(layer "F.Fab")
			(hide yes)
			(effects
				(font
					(size 1 1)
					(thickness 0.15)
				)
			)
		)
		(property "Size" "4.1x4.1mm"
			(at 0 0 270)
			(unlocked yes)
			(layer "F.Fab")
			(hide yes)
			(effects
				(font
					(size 1 1)
					(thickness 0.15)
				)
			)
		)
		(property "Author" "Antmicro"
			(at 0 0 270)
			(unlocked yes)
			(layer "F.Fab")
			(hide yes)
			(effects
				(font
					(size 1 1)
					(thickness 0.15)
				)
			)
		)
		(property "License" "Apache-2.0"
			(at 0 0 270)
			(unlocked yes)
			(layer "F.Fab")
			(hide yes)
			(effects
				(font
					(size 1 1)
					(thickness 0.15)
				)
			)
		)
		(sheetname "/Power/")
		(sheetfile "power.kicad_sch")
		(attr smd)
		(fp_rect
			(start -2.2 -2.2)
			(end 2.2 2.2)
			(stroke
				(width 0.15)
				(type solid)
			)
			(fill no)
			(layer "F.SilkS")
		)
		(fp_rect
			(start -2.3 -2.3)
			(end 2.3 2.3)
			(stroke
				(width 0.05)
				(type solid)
			)
			(fill no)
			(layer "F.CrtYd")
		)
		(fp_rect
			(start -2.05 -2.05)
			(end 2.05 2.05)
			(stroke
				(width 0.15)
				(type solid)
			)
			(fill no)
			(layer "F.Fab")
		)
		(fp_text user "${REFERENCE}"
			(at 0 0 90)
			(layer "F.Fab")
			(effects
				(font
					(size 0.7 0.7)
					(thickness 0.15)
				)
				(justify right top)
			)
		)
		(fp_text user "License: Apache-2.0"
			(at -2.4 5.4 90)
			(layer "F.Fab")
			(effects
				(font
					(size 0.7 0.7)
					(thickness 0.15)
				)
				(justify right top)
			)
		)
		(fp_text user "Author: Antmicro"
			(at -2.4 6.6 90)
			(layer "F.Fab")
			(effects
				(font
					(size 0.7 0.7)
					(thickness 0.15)
				)
				(justify right top)
			)
		)
		(pad "1" smd roundrect
			(at -1.185 0)
			(size 3.7 1)
			(layers "F.Cu" "F.Mask" "F.Paste")
			(roundrect_rratio 0.1)
			(net 86 "/Power/3V3_SW")
			(pintype "passive")
		)
		(pad "2" smd roundrect
			(at 1.185 0)
			(size 3.7 1)
			(layers "F.Cu" "F.Mask" "F.Paste")
			(roundrect_rratio 0.1)
			(net 186 "/Power/3V3_CONV")
			(pintype "passive")
		)
	)
	(footprint "antmicro-footprints:SOT-23-3"
		(layer "F.Cu")
		(at 133.4 71.35 90)
		(property "Reference" "Q8"
			(at 2.406999 -1.4735 90)
			(layer "F.SilkS")
			(effects
				(font
					(size 0.7 0.7)
					(thickness 0.15)
				)
				(justify right top)
			)
		)
		(property "Value" "BSS138-7-F"
			(at -1.9 2.7 90)
			(layer "F.Fab")
			(effects
				(font
					(size 0.7 0.7)
					(thickness 0.15)
				)
				(justify left bottom)
			)
		)
		(property "Datasheet" "https://www.diodes.com/assets/Datasheets/ds30144.pdf"
			(at 0 0 90)
			(layer "F.Fab")
			(hide yes)
			(effects
				(font
					(size 1.27 1.27)
					(thickness 0.15)
				)
			)
		)
		(property "Description" "Power MOSFET, N Channel, 50 V, 200 mA, 1.4 ohm, SOT-23, Surface Mount"
			(at 0 0 90)
			(layer "F.Fab")
			(hide yes)
			(effects
				(font
					(size 1.27 1.27)
					(thickness 0.15)
				)
			)
		)
		(property "MPN" "BSS138-7-F"
			(at 0 0 90)
			(unlocked yes)
			(layer "F.Fab")
			(hide yes)
			(effects
				(font
					(size 1 1)
					(thickness 0.15)
				)
			)
		)
		(property "Manufacturer" "Diodes Incorporated"
			(at 0 0 90)
			(unlocked yes)
			(layer "F.Fab")
			(hide yes)
			(effects
				(font
					(size 1 1)
					(thickness 0.15)
				)
			)
		)
		(property "Author" "Antmicro"
			(at 0 0 90)
			(unlocked yes)
			(layer "F.Fab")
			(hide yes)
			(effects
				(font
					(size 1 1)
					(thickness 0.15)
				)
			)
		)
		(property "License" "Apache-2.0"
			(at 0 0 90)
			(unlocked yes)
			(layer "F.Fab")
			(hide yes)
			(effects
				(font
					(size 1 1)
					(thickness 0.15)
				)
			)
		)
		(sheetname "/USB-PD/")
		(sheetfile "usb-pd.kicad_sch")
		(attr smd)
		(fp_line
			(start 0.7 -1.5)
			(end -0.7 -1.5)
			(stroke
				(width 0.15)
				(type solid)
			)
			(layer "F.SilkS")
		)
		(fp_line
			(start -0.85 -1.35)
			(end -0.7 -1.5)
			(stroke
				(width 0.15)
				(type solid)
			)
			(layer "F.SilkS")
		)
		(fp_line
			(start -1.45 -1.35)
			(end -0.85 -1.35)
			(stroke
				(width 0.15)
				(type solid)
			)
			(layer "F.SilkS")
		)
		(fp_line
			(start 0.7 -0.4)
			(end 0.7 -1.5)
			(stroke
				(width 0.15)
				(type solid)
			)
			(layer "F.SilkS")
		)
		(fp_line
			(start 0.7 0.4)
			(end 0.7 1.5)
			(stroke
				(width 0.15)
				(type solid)
			)
			(layer "F.SilkS")
		)
		(fp_line
			(start 0.7 1.5)
			(end -0.7 1.5)
			(stroke
				(width 0.15)
				(type solid)
			)
			(layer "F.SilkS")
		)
		(fp_line
			(start -0.7 1.5)
			(end -0.7 1.35)
			(stroke
				(width 0.15)
				(type solid)
			)
			(layer "F.SilkS")
		)
		(fp_line
			(start 0.825 -1.6)
			(end 0.825 -0.45)
			(stroke
				(width 0.05)
				(type solid)
			)
			(layer "F.CrtYd")
		)
		(fp_line
			(start -0.9 -1.6)
			(end 0.825 -1.6)
			(stroke
				(width 0.05)
				(type solid)
			)
			(layer "F.CrtYd")
		)
		(fp_line
			(start -0.9 -1.6)
			(end -0.9 -1.4)
			(stroke
				(width 0.05)
				(type solid)
			)
			(layer "F.CrtYd")
		)
		(fp_line
			(start -0.9 -1.4)
			(end -1.75 -1.4)
			(stroke
				(width 0.05)
				(type solid)
			)
			(layer "F.CrtYd")
		)
		(fp_line
			(start -0.85 -0.5)
			(end -1.75 -0.5)
			(stroke
				(width 0.05)
				(type solid)
			)
			(layer "F.CrtYd")
		)
		(fp_line
			(start -1.75 -0.5)
			(end -1.75 -1.4)
			(stroke
				(width 0.05)
				(type solid)
			)
			(layer "F.CrtYd")
		)
		(fp_line
			(start 1.75 -0.45)
			(end 1.75 0.45)
			(stroke
				(width 0.05)
				(type solid)
			)
			(layer "F.CrtYd")
		)
		(fp_line
			(start 0.825 -0.45)
			(end 1.75 -0.45)
			(stroke
				(width 0.05)
				(type solid)
			)
			(layer "F.CrtYd")
		)
		(fp_line
			(start 1.75 0.45)
			(end 0.85 0.45)
			(stroke
				(width 0.05)
				(type solid)
			)
			(layer "F.CrtYd")
		)
		(fp_line
			(start 0.85 0.45)
			(end 0.85 1.65)
			(stroke
				(width 0.05)
				(type solid)
			)
			(layer "F.CrtYd")
		)
		(fp_line
			(start -0.85 0.5)
			(end -0.85 -0.5)
			(stroke
				(width 0.05)
				(type solid)
			)
			(layer "F.CrtYd")
		)
		(fp_line
			(start -1.75 0.5)
			(end -0.85 0.5)
			(stroke
				(width 0.05)
				(type solid)
			)
			(layer "F.CrtYd")
		)
		(fp_line
			(start -0.85 1.4)
			(end -1.75 1.4)
			(stroke
				(width 0.05)
				(type solid)
			)
			(layer "F.CrtYd")
		)
		(fp_line
			(start -1.75 1.4)
			(end -1.75 0.5)
			(stroke
				(width 0.05)
				(type solid)
			)
			(layer "F.CrtYd")
		)
		(fp_line
			(start 0.85 1.65)
			(end -0.85 1.65)
			(stroke
				(width 0.05)
				(type solid)
			)
			(layer "F.CrtYd")
		)
		(fp_line
			(start -0.85 1.65)
			(end -0.85 1.4)
			(stroke
				(width 0.05)
				(type solid)
			)
			(layer "F.CrtYd")
		)
		(fp_line
			(start -0.437 -1.526)
			(end 0.688 -1.526)
			(stroke
				(width 0.15)
				(type solid)
			)
			(layer "F.Fab")
		)
		(fp_line
			(start -0.437 -1.526)
			(end -0.712 -1.325)
			(stroke
				(width 0.15)
				(type solid)
			)
			(layer "F.Fab")
		)
		(fp_line
			(start -0.712 -1.325)
			(end -0.712 1.523)
			(stroke
				(width 0.15)
				(type solid)
			)
			(layer "F.Fab")
		)
		(fp_line
			(start 0.688 1.519)
			(end 0.688 -1.52)
			(stroke
				(width 0.15)
				(type solid)
			)
			(layer "F.Fab")
		)
		(fp_line
			(start -0.712 1.519)
			(end 0.688 1.519)
			(stroke
				(width 0.15)
				(type solid)
			)
			(layer "F.Fab")
		)
		(fp_text user "License: Apache-2.0"
			(at -1.8 6.8 90)
			(layer "F.Fab")
			(effects
				(font
					(size 0.7 0.7)
					(thickness 0.15)
				)
				(justify left bottom)
			)
		)
		(fp_text user "Author: Antmicro"
			(at -1.837 5.3 90)
			(layer "F.Fab")
			(effects
				(font
					(size 0.7 0.7)
					(thickness 0.15)
				)
				(justify left bottom)
			)
		)
		(fp_text user "${REFERENCE}"
			(at 0 0.025 270)
			(layer "F.Fab")
			(effects
				(font
					(size 0.7 0.7)
					(thickness 0.15)
				)
				(justify right top)
			)
		)
		(pad "1" smd roundrect
			(at -1.1 -0.951 90)
			(size 1 0.6)
			(layers "F.Cu" "F.Mask" "F.Paste")
			(roundrect_rratio 0.15)
			(net 124 "/USB-PD/FAULT")
			(pinfunction "G")
			(pintype "input")
		)
		(pad "2" smd roundrect
			(at -1.1 0.949 90)
			(size 1 0.6)
			(layers "F.Cu" "F.Mask" "F.Paste")
			(roundrect_rratio 0.15)
			(net 66 "GND")
			(pinfunction "S")
			(pintype "passive")
		)
		(pad "3" smd roundrect
			(at 1.1 -0.0005 90)
			(size 1 0.6)
			(layers "F.Cu" "F.Mask" "F.Paste")
			(roundrect_rratio 0.15)
			(net 176 "Net-(Q8-D)")
			(pinfunction "D")
			(pintype "passive")
		)
	)
)
